(kicad_pcb
	(version 20260206)
	(generator "pcbnew")
	(generator_version "10.0")
	(general
		(thickness 1.6)
		(legacy_teardrops no)
	)
	(paper "A4")
	(title_block
		(title "9052_F0T_PDB_Converter_Brick_F_V03_1208_1600_OCP.brd")
		(comment 1 "Grand Teton / footprints 111-118 of 578")
	)
	(layers
		(0 "F.Cu" signal "TOP")
		(4 "In1.Cu" signal "GND")
		(6 "In2.Cu" signal "IN1")
		(8 "In3.Cu" signal "GND1")
		(10 "In4.Cu" signal "VCC")
		(12 "In5.Cu" signal "VCC1")
		(14 "In6.Cu" signal "GND2")
		(16 "In7.Cu" signal "IN2")
		(18 "In8.Cu" signal "GND3")
		(2 "B.Cu" signal "BOTTOM")
		(9 "F.Adhes" user "F.Adhesive")
		(11 "B.Adhes" user "B.Adhesive")
		(13 "F.Paste" user "Package Geometry/Pastemask Top")
		(15 "B.Paste" user "Package Geometry/Pastemask Bottom")
		(5 "F.SilkS" user "Ref Des/Silkscreen Top")
		(7 "B.SilkS" user "Ref Des/Silkscreen Bottom")
		(1 "F.Mask" user "Board Geometry/Soldermask Top")
		(3 "B.Mask" user "Board Geometry/Soldermask Bottom")
		(17 "Dwgs.User" user "User.Drawings")
		(19 "Cmts.User" user "User.Comments")
		(21 "Eco1.User" user "User.Eco1")
		(23 "Eco2.User" user "User.Eco2")
		(25 "Edge.Cuts" user "Board Geometry/Outline")
		(27 "Margin" user)
		(31 "F.CrtYd" user "Package Geometry/Place Bound Top")
		(29 "B.CrtYd" user "Package Geometry/Place Bound Bottom")
		(35 "F.Fab" user "Ref Des/Assembly Top")
		(33 "B.Fab" user "Ref Des/Assembly Bottom")
	)
	(footprint ""
		(layer "F.Cu")
		(at 94.238826 -136.906 90)
		(property "Reference" "PC44"
			(at 6.06933 1.011174 0)
			(unlocked yes)
			(layer "F.SilkS")
			(effects
				(font
					(size 0.7874 0.5842)
					(thickness 0.1524)
				)
				(justify left)
			)
		)
		(property "Value" ""
			(at 0 0 90)
			(layer "F.Fab")
			(effects
				(font
					(size 1.27 1.27)
				)
			)
		)
		(duplicate_pad_numbers_are_jumpers no)
		(fp_line
			(start 5.2578 2.499868)
			(end -5.2578 2.499868)
			(stroke
				(width 0.1524)
				(type default)
			)
			(layer "F.SilkS")
		)
		(fp_circle
			(center 0 2.500122)
			(end 0 7.758176)
			(stroke
				(width 0.1524)
				(type default)
			)
			(fill no)
			(layer "F.SilkS")
		)
		(fp_poly
			(pts
				(arc
					(start 5.2578 2.499868)
					(mid 0 7.757922)
					(end -5.2578 2.499868)
				)
			)
			(stroke
				(width 0)
				(type default)
			)
			(fill yes)
			(layer "F.SilkS")
		)
		(fp_circle
			(center 0 2.500122)
			(end 0 7.758176)
			(stroke
				(width 0.1)
				(type default)
			)
			(fill no)
			(layer "F.Fab")
		)
		(pad "1" thru_hole rect
			(at 0 0)
			(size 1.5748 1.5748)
			(drill 1.0668)
			(layers "*.Cu" "*.Mask")
			(remove_unused_layers no)
			(net "P52V_HS_FILTER")
			(clearance 0)
			(padstack
				(mode front_inner_back)
				(layer "Inner"
					(shape circle)
					(size 1.5748 1.5748)
					(clearance 0)
				)
				(layer "B.Cu"
					(shape rect)
					(size 1.5748 1.5748)
					(clearance 0)
				)
			)
		)
		(pad "2" thru_hole circle
			(at 0 4.99999)
			(size 1.5748 1.5748)
			(drill 1.0668)
			(layers "*.Cu" "*.Mask")
			(remove_unused_layers no)
			(net "GND")
			(clearance 0)
		)
	)
	(footprint ""
		(layer "F.Cu")
		(at 234.569 -95.504 -90)
		(property "Reference" "C39"
			(at 0 0 270)
			(layer "F.SilkS")
			(hide yes)
			(effects
				(font
					(size 1.27 1.27)
				)
			)
		)
		(property "Value" ""
			(at 0 0 270)
			(layer "F.Fab")
			(effects
				(font
					(size 1.27 1.27)
				)
			)
		)
		(duplicate_pad_numbers_are_jumpers no)
		(fp_line
			(start -2.2098 0.9398)
			(end -2.2098 -0.9398)
			(stroke
				(width 0.1524)
				(type default)
			)
			(layer "F.SilkS")
		)
		(fp_line
			(start 2.2098 0.9398)
			(end -2.2098 0.9398)
			(stroke
				(width 0.1524)
				(type default)
			)
			(layer "F.SilkS")
		)
		(fp_line
			(start -2.2098 -0.9398)
			(end 2.2098 -0.9398)
			(stroke
				(width 0.1524)
				(type default)
			)
			(layer "F.SilkS")
		)
		(fp_line
			(start 2.2098 -0.9398)
			(end 2.2098 0.9398)
			(stroke
				(width 0.1524)
				(type default)
			)
			(layer "F.SilkS")
		)
		(fp_line
			(start -1.700022 0.899922)
			(end -1.700022 -0.899922)
			(stroke
				(width 0.1)
				(type default)
			)
			(layer "F.Fab")
		)
		(fp_line
			(start 1.700022 0.899922)
			(end -1.700022 0.899922)
			(stroke
				(width 0.1)
				(type default)
			)
			(layer "F.Fab")
		)
		(fp_line
			(start -1.700022 -0.899922)
			(end 1.700022 -0.899922)
			(stroke
				(width 0.1)
				(type default)
			)
			(layer "F.Fab")
		)
		(fp_line
			(start 1.700022 -0.899922)
			(end 1.700022 0.899922)
			(stroke
				(width 0.1)
				(type default)
			)
			(layer "F.Fab")
		)
		(pad "1" smd rect
			(at -1.4732 0 90)
			(size 1.1684 1.5748)
			(layers "F.Cu" "F.Mask" "F.Paste")
			(net "P52V_HS")
		)
		(pad "2" smd rect
			(at 1.4732 0 90)
			(size 1.1684 1.5748)
			(layers "F.Cu" "F.Mask" "F.Paste")
			(net "GND")
		)
	)
	(footprint ""
		(layer "F.Cu")
		(at 146.939 -60.96)
		(property "Reference" "PC40"
			(at -1.27 -3.65633 0)
			(unlocked yes)
			(layer "F.SilkS")
			(effects
				(font
					(size 0.7874 0.5842)
					(thickness 0.1524)
				)
				(justify left)
			)
		)
		(property "Value" ""
			(at 0 0 0)
			(layer "F.Fab")
			(effects
				(font
					(size 1.27 1.27)
				)
			)
		)
		(duplicate_pad_numbers_are_jumpers no)
		(fp_line
			(start 5.2578 2.499868)
			(end -5.2578 2.499868)
			(stroke
				(width 0.1524)
				(type default)
			)
			(layer "F.SilkS")
		)
		(fp_circle
			(center 0 2.499868)
			(end 5.2578 2.499868)
			(stroke
				(width 0.1524)
				(type default)
			)
			(fill no)
			(layer "F.SilkS")
		)
		(fp_poly
			(pts
				(arc
					(start 5.2578 2.499868)
					(mid 0 7.757922)
					(end -5.2578 2.499868)
				)
			)
			(stroke
				(width 0)
				(type default)
			)
			(fill yes)
			(layer "F.SilkS")
		)
		(fp_circle
			(center 0 2.499868)
			(end 5.2578 2.499868)
			(stroke
				(width 0.1)
				(type default)
			)
			(fill no)
			(layer "F.Fab")
		)
		(pad "1" thru_hole rect
			(at 0 0 270)
			(size 1.524 1.524)
			(drill 1.016)
			(layers "*.Cu" "*.Mask")
			(remove_unused_layers no)
			(net "P12V_BRICK")
			(clearance 0)
			(padstack
				(mode front_inner_back)
				(layer "Inner"
					(shape circle)
					(size 1.524 1.524)
					(clearance 0)
				)
				(layer "B.Cu"
					(shape rect)
					(size 1.524 1.524)
					(clearance 0)
				)
			)
		)
		(pad "2" thru_hole circle
			(at 0 4.99999 270)
			(size 1.524 1.524)
			(drill 1.016)
			(layers "*.Cu" "*.Mask")
			(remove_unused_layers no)
			(net "GND")
			(clearance 0)
		)
	)
	(footprint ""
		(layer "F.Cu")
		(at 280.67 -24.765 180)
		(property "Reference" "U19"
			(at 0.3175 2.24663 0)
			(unlocked yes)
			(layer "F.SilkS")
			(effects
				(font
					(size 0.7874 0.5842)
					(thickness 0.1524)
				)
				(justify left)
			)
		)
		(property "Value" ""
			(at 0 0 180)
			(layer "F.Fab")
			(effects
				(font
					(size 1.27 1.27)
				)
			)
		)
		(duplicate_pad_numbers_are_jumpers no)
		(fp_line
			(start 1.733296 1.549908)
			(end 1.733296 -1.549908)
			(stroke
				(width 0.1524)
				(type default)
			)
			(layer "F.SilkS")
		)
		(fp_line
			(start 1.733296 -1.549908)
			(end 0.660908 -1.549908)
			(stroke
				(width 0.1524)
				(type default)
			)
			(layer "F.SilkS")
		)
		(fp_line
			(start 0.660908 -1.549908)
			(end 0 -0.889)
			(stroke
				(width 0.1524)
				(type default)
			)
			(layer "F.SilkS")
		)
		(fp_line
			(start 0 -0.889)
			(end -0.660908 -1.549908)
			(stroke
				(width 0.1524)
				(type default)
			)
			(layer "F.SilkS")
		)
		(fp_line
			(start -0.660908 -1.549908)
			(end -1.733296 -1.549908)
			(stroke
				(width 0.1524)
				(type default)
			)
			(layer "F.SilkS")
		)
		(fp_line
			(start -1.733296 1.549908)
			(end 1.733296 1.549908)
			(stroke
				(width 0.1524)
				(type default)
			)
			(layer "F.SilkS")
		)
		(fp_line
			(start -1.733296 -1.549908)
			(end -1.733296 1.549908)
			(stroke
				(width 0.1524)
				(type default)
			)
			(layer "F.SilkS")
		)
		(fp_poly
			(pts
				(xy -2.4384 -1.20396) (xy -2.4384 -0.69596) (xy -1.9304 -0.94996)
			)
			(stroke
				(width 0)
				(type default)
			)
			(fill yes)
			(layer "F.SilkS")
		)
		(fp_line
			(start 0.849884 1.549908)
			(end 0.849884 -1.549908)
			(stroke
				(width 0.1)
				(type default)
			)
			(layer "F.Fab")
		)
		(fp_line
			(start 0.849884 -1.549908)
			(end -0.849884 -1.549908)
			(stroke
				(width 0.1)
				(type default)
			)
			(layer "F.Fab")
		)
		(fp_line
			(start -0.849884 1.549908)
			(end 0.849884 1.549908)
			(stroke
				(width 0.1)
				(type default)
			)
			(layer "F.Fab")
		)
		(fp_line
			(start -0.849884 -1.549908)
			(end -0.849884 1.549908)
			(stroke
				(width 0.1)
				(type default)
			)
			(layer "F.Fab")
		)
		(fp_poly
			(pts
				(xy -2.4384 -1.20396) (xy -2.4384 -0.69596) (xy -1.9304 -0.94996)
			)
			(stroke
				(width 0)
				(type default)
			)
			(fill yes)
			(layer "F.Fab")
		)
		(pad "1" smd rect
			(at -1.199896 -0.94996 90)
			(size 0.5588 0.8128)
			(layers "F.Cu" "F.Mask" "F.Paste")
			(net "FM_HSC_EN_BUSBAR")
		)
		(pad "2" smd rect
			(at -1.199896 0 90)
			(size 0.5588 0.8128)
			(layers "F.Cu" "F.Mask" "F.Paste")
			(net "FM_HSC_EN_FUSE")
		)
		(pad "3" smd rect
			(at -1.199896 0.94996 90)
			(size 0.5588 0.8128)
			(layers "F.Cu" "F.Mask" "F.Paste")
			(net "GND")
		)
		(pad "4" smd rect
			(at 1.199896 0.94996 90)
			(size 0.5588 0.8128)
			(layers "F.Cu" "F.Mask" "F.Paste")
			(net "P52V_HS1_R_EN")
		)
		(pad "5" smd rect
			(at 1.199896 -0.94996 90)
			(size 0.5588 0.8128)
			(layers "F.Cu" "F.Mask" "F.Paste")
			(net "P3V3_AND")
		)
	)
	(footprint ""
		(layer "F.Cu")
		(at 266.192 -34.798 -90)
		(property "Reference" "PR210"
			(at 0 0 270)
			(layer "F.SilkS")
			(hide yes)
			(effects
				(font
					(size 1.27 1.27)
				)
			)
		)
		(property "Value" ""
			(at 0 0 270)
			(layer "F.Fab")
			(effects
				(font
					(size 1.27 1.27)
				)
			)
		)
		(duplicate_pad_numbers_are_jumpers no)
		(fp_line
			(start -0.7874 0.4064)
			(end -0.7874 -0.4064)
			(stroke
				(width 0.1524)
				(type default)
			)
			(layer "F.SilkS")
		)
		(fp_line
			(start 0.7874 0.4064)
			(end -0.7874 0.4064)
			(stroke
				(width 0.1524)
				(type default)
			)
			(layer "F.SilkS")
		)
		(fp_line
			(start -0.7874 -0.4064)
			(end 0.7874 -0.4064)
			(stroke
				(width 0.1524)
				(type default)
			)
			(layer "F.SilkS")
		)
		(fp_line
			(start 0.7874 -0.4064)
			(end 0.7874 0.4064)
			(stroke
				(width 0.1524)
				(type default)
			)
			(layer "F.SilkS")
		)
		(fp_line
			(start -0.67945 0.3048)
			(end -0.67945 -0.305054)
			(stroke
				(width 0.1)
				(type default)
			)
			(layer "F.Fab")
		)
		(fp_line
			(start -0.12065 0.3048)
			(end -0.67945 0.3048)
			(stroke
				(width 0.1)
				(type default)
			)
			(layer "F.Fab")
		)
		(fp_line
			(start 0.120396 0.3048)
			(end 0.120396 0.2794)
			(stroke
				(width 0.1)
				(type default)
			)
			(layer "F.Fab")
		)
		(fp_line
			(start 0.67945 0.3048)
			(end 0.120396 0.3048)
			(stroke
				(width 0.1)
				(type default)
			)
			(layer "F.Fab")
		)
		(fp_line
			(start -0.12065 0.2794)
			(end -0.12065 0.3048)
			(stroke
				(width 0.1)
				(type default)
			)
			(layer "F.Fab")
		)
		(fp_line
			(start 0.120396 0.2794)
			(end -0.12065 0.2794)
			(stroke
				(width 0.1)
				(type default)
			)
			(layer "F.Fab")
		)
		(fp_line
			(start -0.12065 -0.2794)
			(end 0.12065 -0.2794)
			(stroke
				(width 0.1)
				(type default)
			)
			(layer "F.Fab")
		)
		(fp_line
			(start 0.12065 -0.2794)
			(end 0.12065 -0.3048)
			(stroke
				(width 0.1)
				(type default)
			)
			(layer "F.Fab")
		)
		(fp_line
			(start 0.12065 -0.3048)
			(end 0.67945 -0.3048)
			(stroke
				(width 0.1)
				(type default)
			)
			(layer "F.Fab")
		)
		(fp_line
			(start 0.67945 -0.3048)
			(end 0.67945 0.3048)
			(stroke
				(width 0.1)
				(type default)
			)
			(layer "F.Fab")
		)
		(fp_line
			(start -0.67945 -0.305054)
			(end -0.12065 -0.305054)
			(stroke
				(width 0.1)
				(type default)
			)
			(layer "F.Fab")
		)
		(fp_line
			(start -0.12065 -0.305054)
			(end -0.12065 -0.2794)
			(stroke
				(width 0.1)
				(type default)
			)
			(layer "F.Fab")
		)
		(pad "1" smd circle
			(at -0.40005 0 270)
			(size 0 0)
			(layers "F.Cu" "F.Mask" "F.Paste")
			(net "P52V_HS1_TMR")
		)
		(pad "2" smd circle
			(at 0.40005 0 270)
			(size 0 0)
			(layers "F.Cu" "F.Mask" "F.Paste")
			(net "HS1_TMR1")
		)
	)
	(footprint ""
		(layer "F.Cu")
		(at 279.010872 -39.649146)
		(property "Reference" "R146"
			(at 0 0 0)
			(layer "F.SilkS")
			(hide yes)
			(effects
				(font
					(size 1.27 1.27)
				)
			)
		)
		(property "Value" ""
			(at 0 0 0)
			(layer "F.Fab")
			(effects
				(font
					(size 1.27 1.27)
				)
			)
		)
		(duplicate_pad_numbers_are_jumpers no)
		(fp_line
			(start -0.7874 -0.4064)
			(end 0.7874 -0.4064)
			(stroke
				(width 0.1524)
				(type default)
			)
			(layer "F.SilkS")
		)
		(fp_line
			(start -0.7874 0.4064)
			(end -0.7874 -0.4064)
			(stroke
				(width 0.1524)
				(type default)
			)
			(layer "F.SilkS")
		)
		(fp_line
			(start 0.7874 -0.4064)
			(end 0.7874 0.4064)
			(stroke
				(width 0.1524)
				(type default)
			)
			(layer "F.SilkS")
		)
		(fp_line
			(start 0.7874 0.4064)
			(end -0.7874 0.4064)
			(stroke
				(width 0.1524)
				(type default)
			)
			(layer "F.SilkS")
		)
		(fp_line
			(start -0.67945 -0.305054)
			(end -0.12065 -0.305054)
			(stroke
				(width 0.1)
				(type default)
			)
			(layer "F.Fab")
		)
		(fp_line
			(start -0.67945 0.3048)
			(end -0.67945 -0.305054)
			(stroke
				(width 0.1)
				(type default)
			)
			(layer "F.Fab")
		)
		(fp_line
			(start -0.12065 -0.305054)
			(end -0.12065 -0.2794)
			(stroke
				(width 0.1)
				(type default)
			)
			(layer "F.Fab")
		)
		(fp_line
			(start -0.12065 -0.2794)
			(end 0.12065 -0.2794)
			(stroke
				(width 0.1)
				(type default)
			)
			(layer "F.Fab")
		)
		(fp_line
			(start -0.12065 0.2794)
			(end -0.12065 0.3048)
			(stroke
				(width 0.1)
				(type default)
			)
			(layer "F.Fab")
		)
		(fp_line
			(start -0.12065 0.3048)
			(end -0.67945 0.3048)
			(stroke
				(width 0.1)
				(type default)
			)
			(layer "F.Fab")
		)
		(fp_line
			(start 0.120396 0.2794)
			(end -0.12065 0.2794)
			(stroke
				(width 0.1)
				(type default)
			)
			(layer "F.Fab")
		)
		(fp_line
			(start 0.120396 0.3048)
			(end 0.120396 0.2794)
			(stroke
				(width 0.1)
				(type default)
			)
			(layer "F.Fab")
		)
		(fp_line
			(start 0.12065 -0.3048)
			(end 0.67945 -0.3048)
			(stroke
				(width 0.1)
				(type default)
			)
			(layer "F.Fab")
		)
		(fp_line
			(start 0.12065 -0.2794)
			(end 0.12065 -0.3048)
			(stroke
				(width 0.1)
				(type default)
			)
			(layer "F.Fab")
		)
		(fp_line
			(start 0.67945 -0.3048)
			(end 0.67945 0.3048)
			(stroke
				(width 0.1)
				(type default)
			)
			(layer "F.Fab")
		)
		(fp_line
			(start 0.67945 0.3048)
			(end 0.120396 0.3048)
			(stroke
				(width 0.1)
				(type default)
			)
			(layer "F.Fab")
		)
		(pad "1" smd circle
			(at -0.40005 0)
			(size 0 0)
			(layers "F.Cu" "F.Mask" "F.Paste")
			(net "P3V3_AUX")
		)
		(pad "2" smd circle
			(at 0.40005 0)
			(size 0 0)
			(layers "F.Cu" "F.Mask" "F.Paste")
			(net "SMB_P52V_VPDB_SCL_R2")
		)
	)
	(footprint ""
		(layer "F.Cu")
		(at 30.000194 -135.999982 -90)
		(property "Reference" "H11"
			(at -6.340348 12.093194 0)
			(unlocked yes)
			(layer "F.SilkS")
			(effects
				(font
					(size 0.7874 0.5842)
					(thickness 0.1524)
				)
				(justify left)
			)
		)
		(property "Value" ""
			(at 0 0 270)
			(layer "F.Fab")
			(effects
				(font
					(size 1.27 1.27)
				)
			)
		)
		(duplicate_pad_numbers_are_jumpers no)
		(pad "1" thru_hole oval
			(at 0 0 270)
			(size 10.0076 32.004)
			(drill 3.0226
				(offset 0 10.999978)
			)
			(layers "*.Cu" "*.Mask")
			(remove_unused_layers no)
			(net "GND")
			(clearance -1.995678)
			(padstack
				(mode front_inner_back)
				(layer "Inner"
					(shape circle)
					(size 0 0)
					(clearance 0)
				)
				(layer "B.Cu"
					(shape oval)
					(size 10.0076 32.004)
					(offset 0 10.999978)
					(clearance -1.995678)
				)
			)
		)
	)
	(footprint ""
		(layer "F.Cu")
		(at 278.892 -45.593 180)
		(property "Reference" "PR6933"
			(at 0 0 180)
			(layer "F.SilkS")
			(hide yes)
			(effects
				(font
					(size 1.27 1.27)
				)
			)
		)
		(property "Value" ""
			(at 0 0 180)
			(layer "F.Fab")
			(effects
				(font
					(size 1.27 1.27)
				)
			)
		)
		(duplicate_pad_numbers_are_jumpers no)
		(fp_line
			(start 0.7874 0.4064)
			(end -0.7874 0.4064)
			(stroke
				(width 0.1524)
				(type default)
			)
			(layer "F.SilkS")
		)
		(fp_line
			(start 0.7874 -0.4064)
			(end 0.7874 0.4064)
			(stroke
				(width 0.1524)
				(type default)
			)
			(layer "F.SilkS")
		)
		(fp_line
			(start -0.7874 0.4064)
			(end -0.7874 -0.4064)
			(stroke
				(width 0.1524)
				(type default)
			)
			(layer "F.SilkS")
		)
		(fp_line
			(start -0.7874 -0.4064)
			(end 0.7874 -0.4064)
			(stroke
				(width 0.1524)
				(type default)
			)
			(layer "F.SilkS")
		)
		(fp_line
			(start 0.67945 0.3048)
			(end 0.120396 0.3048)
			(stroke
				(width 0.1)
				(type default)
			)
			(layer "F.Fab")
		)
		(fp_line
			(start 0.67945 -0.3048)
			(end 0.67945 0.3048)
			(stroke
				(width 0.1)
				(type default)
			)
			(layer "F.Fab")
		)
		(fp_line
			(start 0.12065 -0.2794)
			(end 0.12065 -0.3048)
			(stroke
				(width 0.1)
				(type default)
			)
			(layer "F.Fab")
		)
		(fp_line
			(start 0.12065 -0.3048)
			(end 0.67945 -0.3048)
			(stroke
				(width 0.1)
				(type default)
			)
			(layer "F.Fab")
		)
		(fp_line
			(start 0.120396 0.3048)
			(end 0.120396 0.2794)
			(stroke
				(width 0.1)
				(type default)
			)
			(layer "F.Fab")
		)
		(fp_line
			(start 0.120396 0.2794)
			(end -0.12065 0.2794)
			(stroke
				(width 0.1)
				(type default)
			)
			(layer "F.Fab")
		)
		(fp_line
			(start -0.12065 0.3048)
			(end -0.67945 0.3048)
			(stroke
				(width 0.1)
				(type default)
			)
			(layer "F.Fab")
		)
		(fp_line
			(start -0.12065 0.2794)
			(end -0.12065 0.3048)
			(stroke
				(width 0.1)
				(type default)
			)
			(layer "F.Fab")
		)
		(fp_line
			(start -0.12065 -0.2794)
			(end 0.12065 -0.2794)
			(stroke
				(width 0.1)
				(type default)
			)
			(layer "F.Fab")
		)
		(fp_line
			(start -0.12065 -0.305054)
			(end -0.12065 -0.2794)
			(stroke
				(width 0.1)
				(type default)
			)
			(layer "F.Fab")
		)
		(fp_line
			(start -0.67945 0.3048)
			(end -0.67945 -0.305054)
			(stroke
				(width 0.1)
				(type default)
			)
			(layer "F.Fab")
		)
		(fp_line
			(start -0.67945 -0.305054)
			(end -0.12065 -0.305054)
			(stroke
				(width 0.1)
				(type default)
			)
			(layer "F.Fab")
		)
		(pad "1" smd circle
			(at -0.40005 0 180)
			(size 0 0)
			(layers "F.Cu" "F.Mask" "F.Paste")
			(net "P52V_HS1_ISET")
		)
		(pad "2" smd circle
			(at 0.40005 0 180)
			(size 0 0)
			(layers "F.Cu" "F.Mask" "F.Paste")
			(net "P52V_HS1_VCAP")
		)
	)
)
